(kicad_pcb
	(version 20260206)
	(generator "pcbnew")
	(generator_version "10.0")
	(general
		(thickness 1.6)
		(legacy_teardrops no)
	)
	(paper "A4")
	(title_block
		(title "01162023_DA0F0TEBIF0_F0T_Expander_BD_F_brd_V02_OCP.brd")
		(comment 1 "Grand Teton / footprints 7892-7898 of 9728")
	)
	(layers
		(0 "F.Cu" signal "TOP")
		(4 "In1.Cu" signal "GND")
		(6 "In2.Cu" signal "VCC")
		(8 "In3.Cu" signal "VCC1")
		(10 "In4.Cu" signal "GND1")
		(12 "In5.Cu" signal "IN1")
		(14 "In6.Cu" signal "GND2")
		(16 "In7.Cu" signal "IN2")
		(18 "In8.Cu" signal "GND3")
		(20 "In9.Cu" signal "IN3")
		(22 "In10.Cu" signal "GND4")
		(24 "In11.Cu" signal "IN4")
		(26 "In12.Cu" signal "GND5")
		(28 "In13.Cu" signal "IN5")
		(30 "In14.Cu" signal "GND6")
		(32 "In15.Cu" signal "IN6")
		(34 "In16.Cu" signal "GND7")
		(2 "B.Cu" signal "BOTTOM")
		(9 "F.Adhes" user "F.Adhesive")
		(11 "B.Adhes" user "B.Adhesive")
		(13 "F.Paste" user "Package Geometry/Pastemask Top")
		(15 "B.Paste" user "Package Geometry/Pastemask Bottom")
		(5 "F.SilkS" user "Ref Des/Silkscreen Top")
		(7 "B.SilkS" user "Ref Des/Silkscreen Bottom")
		(1 "F.Mask" user "Board Geometry/Soldermask Top")
		(3 "B.Mask" user "Board Geometry/Soldermask Bottom")
		(17 "Dwgs.User" user "User.Drawings")
		(19 "Cmts.User" user "User.Comments")
		(21 "Eco1.User" user "User.Eco1")
		(23 "Eco2.User" user "User.Eco2")
		(25 "Edge.Cuts" user "Board Geometry/Outline")
		(27 "Margin" user)
		(31 "F.CrtYd" user "Package Geometry/Place Bound Top")
		(29 "B.CrtYd" user "Package Geometry/Place Bound Bottom")
		(35 "F.Fab" user "Ref Des/Assembly Top")
		(33 "B.Fab" user "Ref Des/Assembly Bottom")
	)
	(footprint ""
		(layer "B.Cu")
		(at 309.741824 -97.005648 180)
		(property "Reference" "R267"
			(at 0 0 0)
			(layer "B.SilkS")
			(hide yes)
			(effects
				(font
					(size 1.27 1.27)
				)
				(justify mirror)
			)
		)
		(property "Value" ""
			(at 0 0 0)
			(layer "B.Fab")
			(effects
				(font
					(size 1.27 1.27)
				)
				(justify mirror)
			)
		)
		(duplicate_pad_numbers_are_jumpers no)
		(fp_line
			(start 0.7874 0.4064)
			(end 0.7874 -0.4064)
			(stroke
				(width 0.1524)
				(type default)
			)
			(layer "B.SilkS")
		)
		(fp_line
			(start 0.7874 -0.4064)
			(end -0.7874 -0.4064)
			(stroke
				(width 0.1524)
				(type default)
			)
			(layer "B.SilkS")
		)
		(fp_line
			(start -0.7874 0.4064)
			(end 0.7874 0.4064)
			(stroke
				(width 0.1524)
				(type default)
			)
			(layer "B.SilkS")
		)
		(fp_line
			(start -0.7874 -0.4064)
			(end -0.7874 0.4064)
			(stroke
				(width 0.1524)
				(type default)
			)
			(layer "B.SilkS")
		)
		(fp_line
			(start 0.67945 0.3048)
			(end 0.67945 -0.305054)
			(stroke
				(width 0.1)
				(type default)
			)
			(layer "B.Fab")
		)
		(fp_line
			(start 0.67945 -0.305054)
			(end 0.12065 -0.305054)
			(stroke
				(width 0.1)
				(type default)
			)
			(layer "B.Fab")
		)
		(fp_line
			(start 0.12065 0.3048)
			(end 0.67945 0.3048)
			(stroke
				(width 0.1)
				(type default)
			)
			(layer "B.Fab")
		)
		(fp_line
			(start 0.12065 0.2794)
			(end 0.12065 0.3048)
			(stroke
				(width 0.1)
				(type default)
			)
			(layer "B.Fab")
		)
		(fp_line
			(start 0.12065 -0.2794)
			(end -0.12065 -0.2794)
			(stroke
				(width 0.1)
				(type default)
			)
			(layer "B.Fab")
		)
		(fp_line
			(start 0.12065 -0.305054)
			(end 0.12065 -0.2794)
			(stroke
				(width 0.1)
				(type default)
			)
			(layer "B.Fab")
		)
		(fp_line
			(start -0.120396 0.3048)
			(end -0.120396 0.2794)
			(stroke
				(width 0.1)
				(type default)
			)
			(layer "B.Fab")
		)
		(fp_line
			(start -0.120396 0.2794)
			(end 0.12065 0.2794)
			(stroke
				(width 0.1)
				(type default)
			)
			(layer "B.Fab")
		)
		(fp_line
			(start -0.12065 -0.2794)
			(end -0.12065 -0.3048)
			(stroke
				(width 0.1)
				(type default)
			)
			(layer "B.Fab")
		)
		(fp_line
			(start -0.12065 -0.3048)
			(end -0.67945 -0.3048)
			(stroke
				(width 0.1)
				(type default)
			)
			(layer "B.Fab")
		)
		(fp_line
			(start -0.67945 0.3048)
			(end -0.120396 0.3048)
			(stroke
				(width 0.1)
				(type default)
			)
			(layer "B.Fab")
		)
		(fp_line
			(start -0.67945 -0.3048)
			(end -0.67945 0.3048)
			(stroke
				(width 0.1)
				(type default)
			)
			(layer "B.Fab")
		)
		(pad "1" smd circle
			(at 0.40005 0)
			(size 0 0)
			(layers "B.Cu" "B.Mask" "B.Paste")
			(net "NIC5_DATA_IN")
		)
		(pad "2" smd circle
			(at -0.40005 0)
			(size 0 0)
			(layers "B.Cu" "B.Mask" "B.Paste")
			(net "P3V3_NIC5")
		)
	)
	(footprint ""
		(layer "B.Cu")
		(at 100.154994 -331.03185 180)
		(property "Reference" "R1228"
			(at 0 0 0)
			(layer "B.SilkS")
			(hide yes)
			(effects
				(font
					(size 1.27 1.27)
				)
				(justify mirror)
			)
		)
		(property "Value" ""
			(at 0 0 0)
			(layer "B.Fab")
			(effects
				(font
					(size 1.27 1.27)
				)
				(justify mirror)
			)
		)
		(duplicate_pad_numbers_are_jumpers no)
		(fp_line
			(start 0.7874 0.4064)
			(end 0.7874 -0.4064)
			(stroke
				(width 0.1524)
				(type default)
			)
			(layer "B.SilkS")
		)
		(fp_line
			(start 0.7874 -0.4064)
			(end -0.7874 -0.4064)
			(stroke
				(width 0.1524)
				(type default)
			)
			(layer "B.SilkS")
		)
		(fp_line
			(start -0.7874 0.4064)
			(end 0.7874 0.4064)
			(stroke
				(width 0.1524)
				(type default)
			)
			(layer "B.SilkS")
		)
		(fp_line
			(start -0.7874 -0.4064)
			(end -0.7874 0.4064)
			(stroke
				(width 0.1524)
				(type default)
			)
			(layer "B.SilkS")
		)
		(fp_line
			(start 0.67945 0.3048)
			(end 0.67945 -0.305054)
			(stroke
				(width 0.1)
				(type default)
			)
			(layer "B.Fab")
		)
		(fp_line
			(start 0.67945 -0.305054)
			(end 0.12065 -0.305054)
			(stroke
				(width 0.1)
				(type default)
			)
			(layer "B.Fab")
		)
		(fp_line
			(start 0.12065 0.3048)
			(end 0.67945 0.3048)
			(stroke
				(width 0.1)
				(type default)
			)
			(layer "B.Fab")
		)
		(fp_line
			(start 0.12065 0.2794)
			(end 0.12065 0.3048)
			(stroke
				(width 0.1)
				(type default)
			)
			(layer "B.Fab")
		)
		(fp_line
			(start 0.12065 -0.2794)
			(end -0.12065 -0.2794)
			(stroke
				(width 0.1)
				(type default)
			)
			(layer "B.Fab")
		)
		(fp_line
			(start 0.12065 -0.305054)
			(end 0.12065 -0.2794)
			(stroke
				(width 0.1)
				(type default)
			)
			(layer "B.Fab")
		)
		(fp_line
			(start -0.120396 0.3048)
			(end -0.120396 0.2794)
			(stroke
				(width 0.1)
				(type default)
			)
			(layer "B.Fab")
		)
		(fp_line
			(start -0.120396 0.2794)
			(end 0.12065 0.2794)
			(stroke
				(width 0.1)
				(type default)
			)
			(layer "B.Fab")
		)
		(fp_line
			(start -0.12065 -0.2794)
			(end -0.12065 -0.3048)
			(stroke
				(width 0.1)
				(type default)
			)
			(layer "B.Fab")
		)
		(fp_line
			(start -0.12065 -0.3048)
			(end -0.67945 -0.3048)
			(stroke
				(width 0.1)
				(type default)
			)
			(layer "B.Fab")
		)
		(fp_line
			(start -0.67945 0.3048)
			(end -0.120396 0.3048)
			(stroke
				(width 0.1)
				(type default)
			)
			(layer "B.Fab")
		)
		(fp_line
			(start -0.67945 -0.3048)
			(end -0.67945 0.3048)
			(stroke
				(width 0.1)
				(type default)
			)
			(layer "B.Fab")
		)
		(pad "1" smd circle
			(at 0.40005 0)
			(size 0 0)
			(layers "B.Cu" "B.Mask" "B.Paste")
			(net "CLK_100M_DB800ZL_PEX1_S0_R_DN")
		)
		(pad "2" smd circle
			(at -0.40005 0)
			(size 0 0)
			(layers "B.Cu" "B.Mask" "B.Paste")
			(net "CLK_100M_DB800ZL_PEX1_S0_DN")
		)
	)
	(footprint ""
		(layer "B.Cu")
		(at 199.049386 -259.311648 90)
		(property "Reference" "R6336"
			(at 0 0 90)
			(layer "B.SilkS")
			(hide yes)
			(effects
				(font
					(size 1.27 1.27)
				)
				(justify mirror)
			)
		)
		(property "Value" ""
			(at 0 0 90)
			(layer "B.Fab")
			(effects
				(font
					(size 1.27 1.27)
				)
				(justify mirror)
			)
		)
		(duplicate_pad_numbers_are_jumpers no)
		(fp_line
			(start 0.7874 -0.4064)
			(end -0.7874 -0.4064)
			(stroke
				(width 0.1524)
				(type default)
			)
			(layer "B.SilkS")
		)
		(fp_line
			(start -0.7874 -0.4064)
			(end -0.7874 0.4064)
			(stroke
				(width 0.1524)
				(type default)
			)
			(layer "B.SilkS")
		)
		(fp_line
			(start 0.7874 0.4064)
			(end 0.7874 -0.4064)
			(stroke
				(width 0.1524)
				(type default)
			)
			(layer "B.SilkS")
		)
		(fp_line
			(start -0.7874 0.4064)
			(end 0.7874 0.4064)
			(stroke
				(width 0.1524)
				(type default)
			)
			(layer "B.SilkS")
		)
		(fp_line
			(start 0.67945 -0.305054)
			(end 0.12065 -0.305054)
			(stroke
				(width 0.1)
				(type default)
			)
			(layer "B.Fab")
		)
		(fp_line
			(start 0.12065 -0.305054)
			(end 0.12065 -0.2794)
			(stroke
				(width 0.1)
				(type default)
			)
			(layer "B.Fab")
		)
		(fp_line
			(start -0.12065 -0.3048)
			(end -0.67945 -0.3048)
			(stroke
				(width 0.1)
				(type default)
			)
			(layer "B.Fab")
		)
		(fp_line
			(start -0.67945 -0.3048)
			(end -0.67945 0.3048)
			(stroke
				(width 0.1)
				(type default)
			)
			(layer "B.Fab")
		)
		(fp_line
			(start 0.12065 -0.2794)
			(end -0.12065 -0.2794)
			(stroke
				(width 0.1)
				(type default)
			)
			(layer "B.Fab")
		)
		(fp_line
			(start -0.12065 -0.2794)
			(end -0.12065 -0.3048)
			(stroke
				(width 0.1)
				(type default)
			)
			(layer "B.Fab")
		)
		(fp_line
			(start 0.12065 0.2794)
			(end 0.12065 0.3048)
			(stroke
				(width 0.1)
				(type default)
			)
			(layer "B.Fab")
		)
		(fp_line
			(start -0.120396 0.2794)
			(end 0.12065 0.2794)
			(stroke
				(width 0.1)
				(type default)
			)
			(layer "B.Fab")
		)
		(fp_line
			(start 0.67945 0.3048)
			(end 0.67945 -0.305054)
			(stroke
				(width 0.1)
				(type default)
			)
			(layer "B.Fab")
		)
		(fp_line
			(start 0.12065 0.3048)
			(end 0.67945 0.3048)
			(stroke
				(width 0.1)
				(type default)
			)
			(layer "B.Fab")
		)
		(fp_line
			(start -0.120396 0.3048)
			(end -0.120396 0.2794)
			(stroke
				(width 0.1)
				(type default)
			)
			(layer "B.Fab")
		)
		(fp_line
			(start -0.67945 0.3048)
			(end -0.120396 0.3048)
			(stroke
				(width 0.1)
				(type default)
			)
			(layer "B.Fab")
		)
		(pad "1" smd circle
			(at 0.40005 0 270)
			(size 0 0)
			(layers "B.Cu" "B.Mask" "B.Paste")
			(net "P1V8_PEX")
		)
		(pad "2" smd circle
			(at -0.40005 0 270)
			(size 0 0)
			(layers "B.Cu" "B.Mask" "B.Paste")
			(net "PEX_MUX_A0")
		)
	)
	(footprint ""
		(layer "B.Cu")
		(at 100.832412 -380.45009)
		(property "Reference" "R1835"
			(at 0 0 0)
			(layer "B.SilkS")
			(hide yes)
			(effects
				(font
					(size 1.27 1.27)
				)
				(justify mirror)
			)
		)
		(property "Value" ""
			(at 0 0 0)
			(layer "B.Fab")
			(effects
				(font
					(size 1.27 1.27)
				)
				(justify mirror)
			)
		)
		(duplicate_pad_numbers_are_jumpers no)
		(fp_line
			(start -0.7874 -0.4064)
			(end -0.7874 0.4064)
			(stroke
				(width 0.1524)
				(type default)
			)
			(layer "B.SilkS")
		)
		(fp_line
			(start -0.7874 0.4064)
			(end 0.7874 0.4064)
			(stroke
				(width 0.1524)
				(type default)
			)
			(layer "B.SilkS")
		)
		(fp_line
			(start 0.7874 -0.4064)
			(end -0.7874 -0.4064)
			(stroke
				(width 0.1524)
				(type default)
			)
			(layer "B.SilkS")
		)
		(fp_line
			(start 0.7874 0.4064)
			(end 0.7874 -0.4064)
			(stroke
				(width 0.1524)
				(type default)
			)
			(layer "B.SilkS")
		)
		(fp_line
			(start -0.67945 -0.3048)
			(end -0.67945 0.3048)
			(stroke
				(width 0.1)
				(type default)
			)
			(layer "B.Fab")
		)
		(fp_line
			(start -0.67945 0.3048)
			(end -0.120396 0.3048)
			(stroke
				(width 0.1)
				(type default)
			)
			(layer "B.Fab")
		)
		(fp_line
			(start -0.12065 -0.3048)
			(end -0.67945 -0.3048)
			(stroke
				(width 0.1)
				(type default)
			)
			(layer "B.Fab")
		)
		(fp_line
			(start -0.12065 -0.2794)
			(end -0.12065 -0.3048)
			(stroke
				(width 0.1)
				(type default)
			)
			(layer "B.Fab")
		)
		(fp_line
			(start -0.120396 0.2794)
			(end 0.12065 0.2794)
			(stroke
				(width 0.1)
				(type default)
			)
			(layer "B.Fab")
		)
		(fp_line
			(start -0.120396 0.3048)
			(end -0.120396 0.2794)
			(stroke
				(width 0.1)
				(type default)
			)
			(layer "B.Fab")
		)
		(fp_line
			(start 0.12065 -0.305054)
			(end 0.12065 -0.2794)
			(stroke
				(width 0.1)
				(type default)
			)
			(layer "B.Fab")
		)
		(fp_line
			(start 0.12065 -0.2794)
			(end -0.12065 -0.2794)
			(stroke
				(width 0.1)
				(type default)
			)
			(layer "B.Fab")
		)
		(fp_line
			(start 0.12065 0.2794)
			(end 0.12065 0.3048)
			(stroke
				(width 0.1)
				(type default)
			)
			(layer "B.Fab")
		)
		(fp_line
			(start 0.12065 0.3048)
			(end 0.67945 0.3048)
			(stroke
				(width 0.1)
				(type default)
			)
			(layer "B.Fab")
		)
		(fp_line
			(start 0.67945 -0.305054)
			(end 0.12065 -0.305054)
			(stroke
				(width 0.1)
				(type default)
			)
			(layer "B.Fab")
		)
		(fp_line
			(start 0.67945 0.3048)
			(end 0.67945 -0.305054)
			(stroke
				(width 0.1)
				(type default)
			)
			(layer "B.Fab")
		)
		(pad "1" smd circle
			(at 0.40005 0 180)
			(size 0 0)
			(layers "B.Cu" "B.Mask" "B.Paste")
			(net "SMB_GPU_1_R_SCL")
		)
		(pad "2" smd circle
			(at -0.40005 0 180)
			(size 0 0)
			(layers "B.Cu" "B.Mask" "B.Paste")
			(net "SMB_GPU_1_SCL")
		)
	)
	(footprint ""
		(layer "B.Cu")
		(at 109.621828 -355.2952 180)
		(property "Reference" "C4177"
			(at 0 0 0)
			(layer "B.SilkS")
			(hide yes)
			(effects
				(font
					(size 1.27 1.27)
				)
				(justify mirror)
			)
		)
		(property "Value" ""
			(at 0 0 0)
			(layer "B.Fab")
			(effects
				(font
					(size 1.27 1.27)
				)
				(justify mirror)
			)
		)
		(duplicate_pad_numbers_are_jumpers no)
		(fp_line
			(start 0.7874 0.4064)
			(end 0.7874 -0.4064)
			(stroke
				(width 0.1524)
				(type default)
			)
			(layer "B.SilkS")
		)
		(fp_line
			(start 0.7874 -0.4064)
			(end -0.7874 -0.4064)
			(stroke
				(width 0.1524)
				(type default)
			)
			(layer "B.SilkS")
		)
		(fp_line
			(start -0.7874 0.4064)
			(end 0.7874 0.4064)
			(stroke
				(width 0.1524)
				(type default)
			)
			(layer "B.SilkS")
		)
		(fp_line
			(start -0.7874 -0.4064)
			(end -0.7874 0.4064)
			(stroke
				(width 0.1524)
				(type default)
			)
			(layer "B.SilkS")
		)
		(fp_line
			(start 0.67945 0.3048)
			(end 0.67945 -0.305054)
			(stroke
				(width 0.1)
				(type default)
			)
			(layer "B.Fab")
		)
		(fp_line
			(start 0.67945 -0.305054)
			(end 0.12065 -0.305054)
			(stroke
				(width 0.1)
				(type default)
			)
			(layer "B.Fab")
		)
		(fp_line
			(start 0.12065 0.3048)
			(end 0.67945 0.3048)
			(stroke
				(width 0.1)
				(type default)
			)
			(layer "B.Fab")
		)
		(fp_line
			(start 0.12065 0.2794)
			(end 0.12065 0.3048)
			(stroke
				(width 0.1)
				(type default)
			)
			(layer "B.Fab")
		)
		(fp_line
			(start 0.12065 -0.2794)
			(end -0.12065 -0.2794)
			(stroke
				(width 0.1)
				(type default)
			)
			(layer "B.Fab")
		)
		(fp_line
			(start 0.12065 -0.305054)
			(end 0.12065 -0.2794)
			(stroke
				(width 0.1)
				(type default)
			)
			(layer "B.Fab")
		)
		(fp_line
			(start -0.120396 0.3048)
			(end -0.120396 0.2794)
			(stroke
				(width 0.1)
				(type default)
			)
			(layer "B.Fab")
		)
		(fp_line
			(start -0.120396 0.2794)
			(end 0.12065 0.2794)
			(stroke
				(width 0.1)
				(type default)
			)
			(layer "B.Fab")
		)
		(fp_line
			(start -0.12065 -0.2794)
			(end -0.12065 -0.3048)
			(stroke
				(width 0.1)
				(type default)
			)
			(layer "B.Fab")
		)
		(fp_line
			(start -0.12065 -0.3048)
			(end -0.67945 -0.3048)
			(stroke
				(width 0.1)
				(type default)
			)
			(layer "B.Fab")
		)
		(fp_line
			(start -0.67945 0.3048)
			(end -0.120396 0.3048)
			(stroke
				(width 0.1)
				(type default)
			)
			(layer "B.Fab")
		)
		(fp_line
			(start -0.67945 -0.3048)
			(end -0.67945 0.3048)
			(stroke
				(width 0.1)
				(type default)
			)
			(layer "B.Fab")
		)
		(pad "1" smd circle
			(at 0.40005 0)
			(size 0 0)
			(layers "B.Cu" "B.Mask" "B.Paste")
			(net "P3V3_CLK_BUFFER_9ZXL0451E_S3_VZX3P3")
		)
		(pad "2" smd circle
			(at -0.40005 0)
			(size 0 0)
			(layers "B.Cu" "B.Mask" "B.Paste")
			(net "GND")
		)
	)
	(footprint ""
		(layer "B.Cu")
		(at 414.599882 -303.499774 -90)
		(property "Reference" "C3425"
			(at 0 0 90)
			(layer "B.SilkS")
			(hide yes)
			(effects
				(font
					(size 1.27 1.27)
				)
				(justify mirror)
			)
		)
		(property "Value" ""
			(at 0 0 90)
			(layer "B.Fab")
			(effects
				(font
					(size 1.27 1.27)
				)
				(justify mirror)
			)
		)
		(duplicate_pad_numbers_are_jumpers no)
		(fp_line
			(start -0.299974 0.150114)
			(end 0.299974 0.150114)
			(stroke
				(width 0.1)
				(type default)
			)
			(layer "B.Fab")
		)
		(fp_line
			(start 0.299974 0.150114)
			(end 0.299974 -0.150114)
			(stroke
				(width 0.1)
				(type default)
			)
			(layer "B.Fab")
		)
		(fp_line
			(start -0.299974 -0.150114)
			(end -0.299974 0.150114)
			(stroke
				(width 0.1)
				(type default)
			)
			(layer "B.Fab")
		)
		(fp_line
			(start 0.299974 -0.150114)
			(end -0.299974 -0.150114)
			(stroke
				(width 0.1)
				(type default)
			)
			(layer "B.Fab")
		)
		(pad "1" smd rect
			(at 0.2667 0 90)
			(size 0.3048 0.381)
			(layers "B.Cu" "B.Mask" "B.Paste")
			(net "P1V25_PEX3")
		)
		(pad "2" smd rect
			(at -0.2667 0 90)
			(size 0.3048 0.381)
			(layers "B.Cu" "B.Mask" "B.Paste")
			(net "GND")
		)
	)
	(footprint ""
		(layer "B.Cu")
		(at 396.07744 -299.5422 90)
		(property "Reference" "C3545"
			(at 0 0 90)
			(layer "B.SilkS")
			(hide yes)
			(effects
				(font
					(size 1.27 1.27)
				)
				(justify mirror)
			)
		)
		(property "Value" ""
			(at 0 0 90)
			(layer "B.Fab")
			(effects
				(font
					(size 1.27 1.27)
				)
				(justify mirror)
			)
		)
		(duplicate_pad_numbers_are_jumpers no)
		(fp_line
			(start 0.299974 -0.150114)
			(end -0.299974 -0.150114)
			(stroke
				(width 0.1)
				(type default)
			)
			(layer "B.Fab")
		)
		(fp_line
			(start -0.299974 -0.150114)
			(end -0.299974 0.150114)
			(stroke
				(width 0.1)
				(type default)
			)
			(layer "B.Fab")
		)
		(fp_line
			(start 0.299974 0.150114)
			(end 0.299974 -0.150114)
			(stroke
				(width 0.1)
				(type default)
			)
			(layer "B.Fab")
		)
		(fp_line
			(start -0.299974 0.150114)
			(end 0.299974 0.150114)
			(stroke
				(width 0.1)
				(type default)
			)
			(layer "B.Fab")
		)
		(pad "1" smd rect
			(at 0.2667 0 270)
			(size 0.3048 0.381)
			(layers "B.Cu" "B.Mask" "B.Paste")
			(net "PCEPLL0_VDDA18_PEX3")
		)
		(pad "2" smd rect
			(at -0.2667 0 270)
			(size 0.3048 0.381)
			(layers "B.Cu" "B.Mask" "B.Paste")
			(net "GND")
		)
	)
)
